# S9S_MB_2U (Grand Teton) — schematic netlist excerpt (pin names and nets, part order shuffled) for the footprints in the layout excerpt that follows; sources: Cadence DE-HDL packaged netlist, KiCad conversion of 03242023_DA0F0TMBIJ0_F0T_Motherboard_J_brd_V01_OCP.brd

R4895  Q_RES  0 5% EMPTY  pkg 0402LF  page 305 : A = P12V_HSC_TEMP_SDA ; B = SMB_LM75_0_3V3AUX_SDA
C2046  Q_CAP  0.1UF 25V 10% X7R  pkg 0402  page 250 : A = P12V_AUX_ADC_TIC ; B = GND

(kicad_pcb
	(version 20260206)
	(generator "pcbnew")
	(generator_version "10.0")
	(general
		(thickness 1.6)
		(legacy_teardrops no)
	)
	(paper "A4")
	(title_block
		(title "03242023_DA0F0TMBIJ0_F0T_Motherboard_J_brd_V01_OCP.brd")
		(comment 1 "Grand Teton / footprints 2974-2975 of 6105")
	)
	(layers
		(0 "F.Cu" signal "TOP")
		(4 "In1.Cu" signal "GND")
		(6 "In2.Cu" signal "IN1")
		(8 "In3.Cu" signal "GND1")
		(10 "In4.Cu" signal "IN2")
		(12 "In5.Cu" signal "GND2")
		(14 "In6.Cu" signal "IN3")
		(16 "In7.Cu" signal "GND3")
		(18 "In8.Cu" signal "VCC")
		(20 "In9.Cu" signal "VCC1")
		(22 "In10.Cu" signal "GND4")
		(24 "In11.Cu" signal "IN4")
		(26 "In12.Cu" signal "GND5")
		(28 "In13.Cu" signal "IN5")
		(30 "In14.Cu" signal "GND6")
		(32 "In15.Cu" signal "IN6")
		(34 "In16.Cu" signal "GND7")
		(2 "B.Cu" signal "BOTTOM")
		(9 "F.Adhes" user "F.Adhesive")
		(11 "B.Adhes" user "B.Adhesive")
		(13 "F.Paste" user "Package Geometry/Pastemask Top")
		(15 "B.Paste" user "Package Geometry/Pastemask Bottom")
		(5 "F.SilkS" user "Ref Des/Silkscreen Top")
		(7 "B.SilkS" user "Ref Des/Silkscreen Bottom")
		(1 "F.Mask" user "Board Geometry/Soldermask Top")
		(3 "B.Mask" user "Board Geometry/Soldermask Bottom")
		(17 "Dwgs.User" user "User.Drawings")
		(19 "Cmts.User" user "User.Comments")
		(21 "Eco1.User" user "User.Eco1")
		(23 "Eco2.User" user "User.Eco2")
		(25 "Edge.Cuts" user "Board Geometry/Outline")
		(27 "Margin" user)
		(31 "F.CrtYd" user "Package Geometry/Place Bound Top")
		(29 "B.CrtYd" user "Package Geometry/Place Bound Bottom")
		(35 "F.Fab" user "Ref Des/Assembly Top")
		(33 "B.Fab" user "Ref Des/Assembly Bottom")
	)
	(footprint ""
		(layer "F.Cu")
		(at 298.16552 -408.7114)
		(property "Reference" "R4895"
			(at 0 0 0)
			(layer "F.SilkS")
			(hide yes)
			(effects
				(font
					(size 1.27 1.27)
				)
			)
		)
		(property "Value" ""
			(at 0 0 0)
			(layer "F.Fab")
			(effects
				(font
					(size 1.27 1.27)
				)
			)
		)
		(duplicate_pad_numbers_are_jumpers no)
		(fp_line
			(start -0.7874 -0.4064)
			(end 0.7874 -0.4064)
			(stroke
				(width 0.1524)
				(type default)
			)
			(layer "F.SilkS")
		)
		(fp_line
			(start -0.7874 0.4064)
			(end -0.7874 -0.4064)
			(stroke
				(width 0.1524)
				(type default)
			)
			(layer "F.SilkS")
		)
		(fp_line
			(start 0.7874 -0.4064)
			(end 0.7874 0.4064)
			(stroke
				(width 0.1524)
				(type default)
			)
			(layer "F.SilkS")
		)
		(fp_line
			(start 0.7874 0.4064)
			(end -0.7874 0.4064)
			(stroke
				(width 0.1524)
				(type default)
			)
			(layer "F.SilkS")
		)
		(fp_line
			(start -0.67945 -0.305054)
			(end -0.12065 -0.305054)
			(stroke
				(width 0.1)
				(type default)
			)
			(layer "F.Fab")
		)
		(fp_line
			(start -0.67945 0.3048)
			(end -0.67945 -0.305054)
			(stroke
				(width 0.1)
				(type default)
			)
			(layer "F.Fab")
		)
		(fp_line
			(start -0.12065 -0.305054)
			(end -0.12065 -0.2794)
			(stroke
				(width 0.1)
				(type default)
			)
			(layer "F.Fab")
		)
		(fp_line
			(start -0.12065 -0.2794)
			(end 0.12065 -0.2794)
			(stroke
				(width 0.1)
				(type default)
			)
			(layer "F.Fab")
		)
		(fp_line
			(start -0.12065 0.2794)
			(end -0.12065 0.3048)
			(stroke
				(width 0.1)
				(type default)
			)
			(layer "F.Fab")
		)
		(fp_line
			(start -0.12065 0.3048)
			(end -0.67945 0.3048)
			(stroke
				(width 0.1)
				(type default)
			)
			(layer "F.Fab")
		)
		(fp_line
			(start 0.120396 0.2794)
			(end -0.12065 0.2794)
			(stroke
				(width 0.1)
				(type default)
			)
			(layer "F.Fab")
		)
		(fp_line
			(start 0.120396 0.3048)
			(end 0.120396 0.2794)
			(stroke
				(width 0.1)
				(type default)
			)
			(layer "F.Fab")
		)
		(fp_line
			(start 0.12065 -0.3048)
			(end 0.67945 -0.3048)
			(stroke
				(width 0.1)
				(type default)
			)
			(layer "F.Fab")
		)
		(fp_line
			(start 0.12065 -0.2794)
			(end 0.12065 -0.3048)
			(stroke
				(width 0.1)
				(type default)
			)
			(layer "F.Fab")
		)
		(fp_line
			(start 0.67945 -0.3048)
			(end 0.67945 0.3048)
			(stroke
				(width 0.1)
				(type default)
			)
			(layer "F.Fab")
		)
		(fp_line
			(start 0.67945 0.3048)
			(end 0.120396 0.3048)
			(stroke
				(width 0.1)
				(type default)
			)
			(layer "F.Fab")
		)
		(pad "1" smd circle
			(at -0.40005 0)
			(size 0 0)
			(layers "F.Cu" "F.Mask" "F.Paste")
			(net "P12V_HSC_TEMP_SDA")
		)
		(pad "2" smd circle
			(at 0.40005 0)
			(size 0 0)
			(layers "F.Cu" "F.Mask" "F.Paste")
			(net "SMB_LM75_0_3V3AUX_SDA")
		)
	)
	(footprint ""
		(layer "F.Cu")
		(at 36.930584 -112.619282)
		(property "Reference" "C2046"
			(at 0 0 0)
			(layer "F.SilkS")
			(hide yes)
			(effects
				(font
					(size 1.27 1.27)
				)
			)
		)
		(property "Value" ""
			(at 0 0 0)
			(layer "F.Fab")
			(effects
				(font
					(size 1.27 1.27)
				)
			)
		)
		(duplicate_pad_numbers_are_jumpers no)
		(fp_line
			(start -0.7874 -0.4064)
			(end 0.7874 -0.4064)
			(stroke
				(width 0.1524)
				(type default)
			)
			(layer "F.SilkS")
		)
		(fp_line
			(start -0.7874 0.4064)
			(end -0.7874 -0.4064)
			(stroke
				(width 0.1524)
				(type default)
			)
			(layer "F.SilkS")
		)
		(fp_line
			(start 0.7874 -0.4064)
			(end 0.7874 0.4064)
			(stroke
				(width 0.1524)
				(type default)
			)
			(layer "F.SilkS")
		)
		(fp_line
			(start 0.7874 0.4064)
			(end -0.7874 0.4064)
			(stroke
				(width 0.1524)
				(type default)
			)
			(layer "F.SilkS")
		)
		(fp_line
			(start -0.67945 -0.305054)
			(end -0.12065 -0.305054)
			(stroke
				(width 0.1)
				(type default)
			)
			(layer "F.Fab")
		)
		(fp_line
			(start -0.67945 0.3048)
			(end -0.67945 -0.305054)
			(stroke
				(width 0.1)
				(type default)
			)
			(layer "F.Fab")
		)
		(fp_line
			(start -0.12065 -0.305054)
			(end -0.12065 -0.2794)
			(stroke
				(width 0.1)
				(type default)
			)
			(layer "F.Fab")
		)
		(fp_line
			(start -0.12065 -0.2794)
			(end 0.12065 -0.2794)
			(stroke
				(width 0.1)
				(type default)
			)
			(layer "F.Fab")
		)
		(fp_line
			(start -0.12065 0.2794)
			(end -0.12065 0.3048)
			(stroke
				(width 0.1)
				(type default)
			)
			(layer "F.Fab")
		)
		(fp_line
			(start -0.12065 0.3048)
			(end -0.67945 0.3048)
			(stroke
				(width 0.1)
				(type default)
			)
			(layer "F.Fab")
		)
		(fp_line
			(start 0.120396 0.2794)
			(end -0.12065 0.2794)
			(stroke
				(width 0.1)
				(type default)
			)
			(layer "F.Fab")
		)
		(fp_line
			(start 0.120396 0.3048)
			(end 0.120396 0.2794)
			(stroke
				(width 0.1)
				(type default)
			)
			(layer "F.Fab")
		)
		(fp_line
			(start 0.12065 -0.3048)
			(end 0.67945 -0.3048)
			(stroke
				(width 0.1)
				(type default)
			)
			(layer "F.Fab")
		)
		(fp_line
			(start 0.12065 -0.2794)
			(end 0.12065 -0.3048)
			(stroke
				(width 0.1)
				(type default)
			)
			(layer "F.Fab")
		)
		(fp_line
			(start 0.67945 -0.3048)
			(end 0.67945 0.3048)
			(stroke
				(width 0.1)
				(type default)
			)
			(layer "F.Fab")
		)
		(fp_line
			(start 0.67945 0.3048)
			(end 0.120396 0.3048)
			(stroke
				(width 0.1)
				(type default)
			)
			(layer "F.Fab")
		)
		(pad "1" smd circle
			(at -0.40005 0)
			(size 0 0)
			(layers "F.Cu" "F.Mask" "F.Paste")
			(net "P12V_AUX_ADC_TIC")
		)
		(pad "2" smd circle
			(at 0.40005 0)
			(size 0 0)
			(layers "F.Cu" "F.Mask" "F.Paste")
			(net "GND")
		)
	)
)
